(kicad_pcb
	(version 20260206)
	(generator "pcbnew")
	(generator_version "10.0")
	(general
		(thickness 1.6)
		(legacy_teardrops no)
	)
	(paper "A4")
	(title_block
		(title "04192023_DAF0TMB3IC0_F0TG_MB_C_brd_V02_OCP.brd")
		(comment 1 "Grand Teton / footprints 2140-2145 of 8354")
	)
	(layers
		(0 "F.Cu" signal "TOP")
		(4 "In1.Cu" signal "GND")
		(6 "In2.Cu" signal "IN1")
		(8 "In3.Cu" signal "GND1")
		(10 "In4.Cu" signal "IN2")
		(12 "In5.Cu" signal "GND2")
		(14 "In6.Cu" signal "IN3")
		(16 "In7.Cu" signal "GND3")
		(18 "In8.Cu" signal "VCC")
		(20 "In9.Cu" signal "VCC1")
		(22 "In10.Cu" signal "GND4")
		(24 "In11.Cu" signal "IN4")
		(26 "In12.Cu" signal "GND5")
		(28 "In13.Cu" signal "IN5")
		(30 "In14.Cu" signal "GND6")
		(32 "In15.Cu" signal "IN6")
		(34 "In16.Cu" signal "GND7")
		(2 "B.Cu" signal "BOTTOM")
		(9 "F.Adhes" user "F.Adhesive")
		(11 "B.Adhes" user "B.Adhesive")
		(13 "F.Paste" user "Package Geometry/Pastemask Top")
		(15 "B.Paste" user "Package Geometry/Pastemask Bottom")
		(5 "F.SilkS" user "Ref Des/Silkscreen Top")
		(7 "B.SilkS" user "Ref Des/Silkscreen Bottom")
		(1 "F.Mask" user "Board Geometry/Soldermask Top")
		(3 "B.Mask" user "Board Geometry/Soldermask Bottom")
		(17 "Dwgs.User" user "User.Drawings")
		(19 "Cmts.User" user "User.Comments")
		(21 "Eco1.User" user "User.Eco1")
		(23 "Eco2.User" user "User.Eco2")
		(25 "Edge.Cuts" user "Board Geometry/Outline")
		(27 "Margin" user)
		(31 "F.CrtYd" user "Package Geometry/Place Bound Top")
		(29 "B.CrtYd" user "Package Geometry/Place Bound Bottom")
		(35 "F.Fab" user "Ref Des/Assembly Top")
		(33 "B.Fab" user "Ref Des/Assembly Bottom")
	)
	(footprint ""
		(layer "F.Cu")
		(at 376.35815 -182.745634 90)
		(property "Reference" "PC478_C0P0_2"
			(at 0 0 90)
			(layer "F.SilkS")
			(hide yes)
			(effects
				(font
					(size 1.27 1.27)
				)
			)
		)
		(property "Value" ""
			(at 0 0 90)
			(layer "F.Fab")
			(effects
				(font
					(size 1.27 1.27)
				)
			)
		)
		(duplicate_pad_numbers_are_jumpers no)
		(fp_line
			(start 0.7874 -0.4064)
			(end 0.7874 0.4064)
			(stroke
				(width 0.1524)
				(type default)
			)
			(layer "F.SilkS")
		)
		(fp_line
			(start -0.7874 -0.4064)
			(end 0.7874 -0.4064)
			(stroke
				(width 0.1524)
				(type default)
			)
			(layer "F.SilkS")
		)
		(fp_line
			(start 0.7874 0.4064)
			(end -0.7874 0.4064)
			(stroke
				(width 0.1524)
				(type default)
			)
			(layer "F.SilkS")
		)
		(fp_line
			(start -0.7874 0.4064)
			(end -0.7874 -0.4064)
			(stroke
				(width 0.1524)
				(type default)
			)
			(layer "F.SilkS")
		)
		(fp_line
			(start -0.12065 -0.305054)
			(end -0.12065 -0.2794)
			(stroke
				(width 0.1)
				(type default)
			)
			(layer "F.Fab")
		)
		(fp_line
			(start -0.67945 -0.305054)
			(end -0.12065 -0.305054)
			(stroke
				(width 0.1)
				(type default)
			)
			(layer "F.Fab")
		)
		(fp_line
			(start 0.67945 -0.3048)
			(end 0.67945 0.3048)
			(stroke
				(width 0.1)
				(type default)
			)
			(layer "F.Fab")
		)
		(fp_line
			(start 0.12065 -0.3048)
			(end 0.67945 -0.3048)
			(stroke
				(width 0.1)
				(type default)
			)
			(layer "F.Fab")
		)
		(fp_line
			(start 0.12065 -0.2794)
			(end 0.12065 -0.3048)
			(stroke
				(width 0.1)
				(type default)
			)
			(layer "F.Fab")
		)
		(fp_line
			(start -0.12065 -0.2794)
			(end 0.12065 -0.2794)
			(stroke
				(width 0.1)
				(type default)
			)
			(layer "F.Fab")
		)
		(fp_line
			(start 0.120396 0.2794)
			(end -0.12065 0.2794)
			(stroke
				(width 0.1)
				(type default)
			)
			(layer "F.Fab")
		)
		(fp_line
			(start -0.12065 0.2794)
			(end -0.12065 0.3048)
			(stroke
				(width 0.1)
				(type default)
			)
			(layer "F.Fab")
		)
		(fp_line
			(start 0.67945 0.3048)
			(end 0.120396 0.3048)
			(stroke
				(width 0.1)
				(type default)
			)
			(layer "F.Fab")
		)
		(fp_line
			(start 0.120396 0.3048)
			(end 0.120396 0.2794)
			(stroke
				(width 0.1)
				(type default)
			)
			(layer "F.Fab")
		)
		(fp_line
			(start -0.12065 0.3048)
			(end -0.67945 0.3048)
			(stroke
				(width 0.1)
				(type default)
			)
			(layer "F.Fab")
		)
		(fp_line
			(start -0.67945 0.3048)
			(end -0.67945 -0.305054)
			(stroke
				(width 0.1)
				(type default)
			)
			(layer "F.Fab")
		)
		(pad "1" smd circle
			(at -0.40005 0 90)
			(size 0 0)
			(layers "F.Cu" "F.Mask" "F.Paste")
			(net "PVDDCR_CPU0_P0_PVCC")
		)
		(pad "2" smd circle
			(at 0.40005 0 90)
			(size 0 0)
			(layers "F.Cu" "F.Mask" "F.Paste")
			(net "GND")
		)
	)
	(footprint ""
		(layer "F.Cu")
		(at 285.48838 -351.368106 -90)
		(property "Reference" "PC186"
			(at 0 0 270)
			(layer "F.SilkS")
			(hide yes)
			(effects
				(font
					(size 1.27 1.27)
				)
			)
		)
		(property "Value" ""
			(at 0 0 270)
			(layer "F.Fab")
			(effects
				(font
					(size 1.27 1.27)
				)
			)
		)
		(duplicate_pad_numbers_are_jumpers no)
		(fp_line
			(start -0.7874 0.4064)
			(end -0.7874 -0.4064)
			(stroke
				(width 0.1524)
				(type default)
			)
			(layer "F.SilkS")
		)
		(fp_line
			(start 0.7874 0.4064)
			(end -0.7874 0.4064)
			(stroke
				(width 0.1524)
				(type default)
			)
			(layer "F.SilkS")
		)
		(fp_line
			(start -0.7874 -0.4064)
			(end 0.7874 -0.4064)
			(stroke
				(width 0.1524)
				(type default)
			)
			(layer "F.SilkS")
		)
		(fp_line
			(start 0.7874 -0.4064)
			(end 0.7874 0.4064)
			(stroke
				(width 0.1524)
				(type default)
			)
			(layer "F.SilkS")
		)
		(fp_line
			(start -0.67945 0.3048)
			(end -0.67945 -0.305054)
			(stroke
				(width 0.1)
				(type default)
			)
			(layer "F.Fab")
		)
		(fp_line
			(start -0.12065 0.3048)
			(end -0.67945 0.3048)
			(stroke
				(width 0.1)
				(type default)
			)
			(layer "F.Fab")
		)
		(fp_line
			(start 0.120396 0.3048)
			(end 0.120396 0.2794)
			(stroke
				(width 0.1)
				(type default)
			)
			(layer "F.Fab")
		)
		(fp_line
			(start 0.67945 0.3048)
			(end 0.120396 0.3048)
			(stroke
				(width 0.1)
				(type default)
			)
			(layer "F.Fab")
		)
		(fp_line
			(start -0.12065 0.2794)
			(end -0.12065 0.3048)
			(stroke
				(width 0.1)
				(type default)
			)
			(layer "F.Fab")
		)
		(fp_line
			(start 0.120396 0.2794)
			(end -0.12065 0.2794)
			(stroke
				(width 0.1)
				(type default)
			)
			(layer "F.Fab")
		)
		(fp_line
			(start -0.12065 -0.2794)
			(end 0.12065 -0.2794)
			(stroke
				(width 0.1)
				(type default)
			)
			(layer "F.Fab")
		)
		(fp_line
			(start 0.12065 -0.2794)
			(end 0.12065 -0.3048)
			(stroke
				(width 0.1)
				(type default)
			)
			(layer "F.Fab")
		)
		(fp_line
			(start 0.12065 -0.3048)
			(end 0.67945 -0.3048)
			(stroke
				(width 0.1)
				(type default)
			)
			(layer "F.Fab")
		)
		(fp_line
			(start 0.67945 -0.3048)
			(end 0.67945 0.3048)
			(stroke
				(width 0.1)
				(type default)
			)
			(layer "F.Fab")
		)
		(fp_line
			(start -0.67945 -0.305054)
			(end -0.12065 -0.305054)
			(stroke
				(width 0.1)
				(type default)
			)
			(layer "F.Fab")
		)
		(fp_line
			(start -0.12065 -0.305054)
			(end -0.12065 -0.2794)
			(stroke
				(width 0.1)
				(type default)
			)
			(layer "F.Fab")
		)
		(pad "1" smd circle
			(at -0.40005 0 270)
			(size 0 0)
			(layers "F.Cu" "F.Mask" "F.Paste")
			(net "SW_PVDDIO_P0_BOOT3_R")
		)
		(pad "2" smd circle
			(at 0.40005 0 270)
			(size 0 0)
			(layers "F.Cu" "F.Mask" "F.Paste")
			(net "SW_PVDDIO_P0_BOOTR3")
		)
	)
	(footprint ""
		(layer "F.Cu")
		(at 287.336992 -346.866464 -90)
		(property "Reference" "PC179_3"
			(at 0 0 270)
			(layer "F.SilkS")
			(hide yes)
			(effects
				(font
					(size 1.27 1.27)
				)
			)
		)
		(property "Value" ""
			(at 0 0 270)
			(layer "F.Fab")
			(effects
				(font
					(size 1.27 1.27)
				)
			)
		)
		(duplicate_pad_numbers_are_jumpers no)
		(fp_line
			(start -0.7874 0.4064)
			(end -0.7874 -0.4064)
			(stroke
				(width 0.1524)
				(type default)
			)
			(layer "F.SilkS")
		)
		(fp_line
			(start 0.7874 0.4064)
			(end -0.7874 0.4064)
			(stroke
				(width 0.1524)
				(type default)
			)
			(layer "F.SilkS")
		)
		(fp_line
			(start -0.7874 -0.4064)
			(end 0.7874 -0.4064)
			(stroke
				(width 0.1524)
				(type default)
			)
			(layer "F.SilkS")
		)
		(fp_line
			(start 0.7874 -0.4064)
			(end 0.7874 0.4064)
			(stroke
				(width 0.1524)
				(type default)
			)
			(layer "F.SilkS")
		)
		(fp_line
			(start -0.67945 0.3048)
			(end -0.67945 -0.305054)
			(stroke
				(width 0.1)
				(type default)
			)
			(layer "F.Fab")
		)
		(fp_line
			(start -0.12065 0.3048)
			(end -0.67945 0.3048)
			(stroke
				(width 0.1)
				(type default)
			)
			(layer "F.Fab")
		)
		(fp_line
			(start 0.120396 0.3048)
			(end 0.120396 0.2794)
			(stroke
				(width 0.1)
				(type default)
			)
			(layer "F.Fab")
		)
		(fp_line
			(start 0.67945 0.3048)
			(end 0.120396 0.3048)
			(stroke
				(width 0.1)
				(type default)
			)
			(layer "F.Fab")
		)
		(fp_line
			(start -0.12065 0.2794)
			(end -0.12065 0.3048)
			(stroke
				(width 0.1)
				(type default)
			)
			(layer "F.Fab")
		)
		(fp_line
			(start 0.120396 0.2794)
			(end -0.12065 0.2794)
			(stroke
				(width 0.1)
				(type default)
			)
			(layer "F.Fab")
		)
		(fp_line
			(start -0.12065 -0.2794)
			(end 0.12065 -0.2794)
			(stroke
				(width 0.1)
				(type default)
			)
			(layer "F.Fab")
		)
		(fp_line
			(start 0.12065 -0.2794)
			(end 0.12065 -0.3048)
			(stroke
				(width 0.1)
				(type default)
			)
			(layer "F.Fab")
		)
		(fp_line
			(start 0.12065 -0.3048)
			(end 0.67945 -0.3048)
			(stroke
				(width 0.1)
				(type default)
			)
			(layer "F.Fab")
		)
		(fp_line
			(start 0.67945 -0.3048)
			(end 0.67945 0.3048)
			(stroke
				(width 0.1)
				(type default)
			)
			(layer "F.Fab")
		)
		(fp_line
			(start -0.67945 -0.305054)
			(end -0.12065 -0.305054)
			(stroke
				(width 0.1)
				(type default)
			)
			(layer "F.Fab")
		)
		(fp_line
			(start -0.12065 -0.305054)
			(end -0.12065 -0.2794)
			(stroke
				(width 0.1)
				(type default)
			)
			(layer "F.Fab")
		)
		(pad "1" smd circle
			(at -0.40005 0 270)
			(size 0 0)
			(layers "F.Cu" "F.Mask" "F.Paste")
			(net "SW_P12V_AUX_PVDDIO_P0_FLT")
		)
		(pad "2" smd circle
			(at 0.40005 0 270)
			(size 0 0)
			(layers "F.Cu" "F.Mask" "F.Paste")
			(net "GND")
		)
	)
	(footprint ""
		(layer "F.Cu")
		(at 41.503854 -349.386398 90)
		(property "Reference" "PC432"
			(at 0 0 90)
			(layer "F.SilkS")
			(hide yes)
			(effects
				(font
					(size 1.27 1.27)
				)
			)
		)
		(property "Value" ""
			(at 0 0 90)
			(layer "F.Fab")
			(effects
				(font
					(size 1.27 1.27)
				)
			)
		)
		(duplicate_pad_numbers_are_jumpers no)
		(fp_line
			(start 0.7874 -0.4064)
			(end 0.7874 0.4064)
			(stroke
				(width 0.1524)
				(type default)
			)
			(layer "F.SilkS")
		)
		(fp_line
			(start -0.7874 -0.4064)
			(end 0.7874 -0.4064)
			(stroke
				(width 0.1524)
				(type default)
			)
			(layer "F.SilkS")
		)
		(fp_line
			(start 0.7874 0.4064)
			(end 0.498602 0.4064)
			(stroke
				(width 0.1524)
				(type default)
			)
			(layer "F.SilkS")
		)
		(fp_line
			(start -0.314198 0.4064)
			(end -0.7874 0.4064)
			(stroke
				(width 0.1524)
				(type default)
			)
			(layer "F.SilkS")
		)
		(fp_line
			(start -0.7874 0.4064)
			(end -0.7874 -0.4064)
			(stroke
				(width 0.1524)
				(type default)
			)
			(layer "F.SilkS")
		)
		(fp_line
			(start -0.12065 -0.305054)
			(end -0.12065 -0.2794)
			(stroke
				(width 0.1)
				(type default)
			)
			(layer "F.Fab")
		)
		(fp_line
			(start -0.67945 -0.305054)
			(end -0.12065 -0.305054)
			(stroke
				(width 0.1)
				(type default)
			)
			(layer "F.Fab")
		)
		(fp_line
			(start 0.67945 -0.3048)
			(end 0.67945 0.3048)
			(stroke
				(width 0.1)
				(type default)
			)
			(layer "F.Fab")
		)
		(fp_line
			(start 0.12065 -0.3048)
			(end 0.67945 -0.3048)
			(stroke
				(width 0.1)
				(type default)
			)
			(layer "F.Fab")
		)
		(fp_line
			(start 0.12065 -0.2794)
			(end 0.12065 -0.3048)
			(stroke
				(width 0.1)
				(type default)
			)
			(layer "F.Fab")
		)
		(fp_line
			(start -0.12065 -0.2794)
			(end 0.12065 -0.2794)
			(stroke
				(width 0.1)
				(type default)
			)
			(layer "F.Fab")
		)
		(fp_line
			(start 0.120396 0.2794)
			(end -0.12065 0.2794)
			(stroke
				(width 0.1)
				(type default)
			)
			(layer "F.Fab")
		)
		(fp_line
			(start -0.12065 0.2794)
			(end -0.12065 0.3048)
			(stroke
				(width 0.1)
				(type default)
			)
			(layer "F.Fab")
		)
		(fp_line
			(start 0.67945 0.3048)
			(end 0.120396 0.3048)
			(stroke
				(width 0.1)
				(type default)
			)
			(layer "F.Fab")
		)
		(fp_line
			(start 0.120396 0.3048)
			(end 0.120396 0.2794)
			(stroke
				(width 0.1)
				(type default)
			)
			(layer "F.Fab")
		)
		(fp_line
			(start -0.12065 0.3048)
			(end -0.67945 0.3048)
			(stroke
				(width 0.1)
				(type default)
			)
			(layer "F.Fab")
		)
		(fp_line
			(start -0.67945 0.3048)
			(end -0.67945 -0.305054)
			(stroke
				(width 0.1)
				(type default)
			)
			(layer "F.Fab")
		)
		(pad "1" smd circle
			(at -0.40005 0 90)
			(size 0 0)
			(layers "F.Cu" "F.Mask" "F.Paste")
			(net "PVDDIO_P1_VCC2")
		)
		(pad "2" smd circle
			(at 0.40005 0 90)
			(size 0 0)
			(layers "F.Cu" "F.Mask" "F.Paste")
			(net "GND")
		)
	)
	(footprint ""
		(layer "F.Cu")
		(at 415.798 -96.901 180)
		(property "Reference" "C8008"
			(at 0 0 180)
			(layer "F.SilkS")
			(hide yes)
			(effects
				(font
					(size 1.27 1.27)
				)
			)
		)
		(property "Value" ""
			(at 0 0 180)
			(layer "F.Fab")
			(effects
				(font
					(size 1.27 1.27)
				)
			)
		)
		(duplicate_pad_numbers_are_jumpers no)
		(fp_line
			(start 0.7874 0.4064)
			(end -0.7874 0.4064)
			(stroke
				(width 0.1524)
				(type default)
			)
			(layer "F.SilkS")
		)
		(fp_line
			(start 0.7874 -0.4064)
			(end 0.7874 0.4064)
			(stroke
				(width 0.1524)
				(type default)
			)
			(layer "F.SilkS")
		)
		(fp_line
			(start -0.7874 0.4064)
			(end -0.7874 -0.4064)
			(stroke
				(width 0.1524)
				(type default)
			)
			(layer "F.SilkS")
		)
		(fp_line
			(start -0.7874 -0.4064)
			(end 0.7874 -0.4064)
			(stroke
				(width 0.1524)
				(type default)
			)
			(layer "F.SilkS")
		)
		(fp_line
			(start 0.67945 0.3048)
			(end 0.120396 0.3048)
			(stroke
				(width 0.1)
				(type default)
			)
			(layer "F.Fab")
		)
		(fp_line
			(start 0.67945 -0.3048)
			(end 0.67945 0.3048)
			(stroke
				(width 0.1)
				(type default)
			)
			(layer "F.Fab")
		)
		(fp_line
			(start 0.12065 -0.2794)
			(end 0.12065 -0.3048)
			(stroke
				(width 0.1)
				(type default)
			)
			(layer "F.Fab")
		)
		(fp_line
			(start 0.12065 -0.3048)
			(end 0.67945 -0.3048)
			(stroke
				(width 0.1)
				(type default)
			)
			(layer "F.Fab")
		)
		(fp_line
			(start 0.120396 0.3048)
			(end 0.120396 0.2794)
			(stroke
				(width 0.1)
				(type default)
			)
			(layer "F.Fab")
		)
		(fp_line
			(start 0.120396 0.2794)
			(end -0.12065 0.2794)
			(stroke
				(width 0.1)
				(type default)
			)
			(layer "F.Fab")
		)
		(fp_line
			(start -0.12065 0.3048)
			(end -0.67945 0.3048)
			(stroke
				(width 0.1)
				(type default)
			)
			(layer "F.Fab")
		)
		(fp_line
			(start -0.12065 0.2794)
			(end -0.12065 0.3048)
			(stroke
				(width 0.1)
				(type default)
			)
			(layer "F.Fab")
		)
		(fp_line
			(start -0.12065 -0.2794)
			(end 0.12065 -0.2794)
			(stroke
				(width 0.1)
				(type default)
			)
			(layer "F.Fab")
		)
		(fp_line
			(start -0.12065 -0.305054)
			(end -0.12065 -0.2794)
			(stroke
				(width 0.1)
				(type default)
			)
			(layer "F.Fab")
		)
		(fp_line
			(start -0.67945 0.3048)
			(end -0.67945 -0.305054)
			(stroke
				(width 0.1)
				(type default)
			)
			(layer "F.Fab")
		)
		(fp_line
			(start -0.67945 -0.305054)
			(end -0.12065 -0.305054)
			(stroke
				(width 0.1)
				(type default)
			)
			(layer "F.Fab")
		)
		(pad "1" smd circle
			(at -0.40005 0 180)
			(size 0 0)
			(layers "F.Cu" "F.Mask" "F.Paste")
			(net "P3V3_OCP_SFF_R")
		)
		(pad "2" smd circle
			(at 0.40005 0 180)
			(size 0 0)
			(layers "F.Cu" "F.Mask" "F.Paste")
			(net "GND")
		)
	)
	(footprint ""
		(layer "F.Cu")
		(at 12.351004 -139.25804 90)
		(property "Reference" "R4079"
			(at 0 0 90)
			(layer "F.SilkS")
			(hide yes)
			(effects
				(font
					(size 1.27 1.27)
				)
			)
		)
		(property "Value" ""
			(at 0 0 90)
			(layer "F.Fab")
			(effects
				(font
					(size 1.27 1.27)
				)
			)
		)
		(duplicate_pad_numbers_are_jumpers no)
		(fp_line
			(start 0.7874 -0.4064)
			(end 0.7874 0.4064)
			(stroke
				(width 0.1524)
				(type default)
			)
			(layer "F.SilkS")
		)
		(fp_line
			(start -0.7874 -0.4064)
			(end 0.7874 -0.4064)
			(stroke
				(width 0.1524)
				(type default)
			)
			(layer "F.SilkS")
		)
		(fp_line
			(start 0.7874 0.4064)
			(end -0.7874 0.4064)
			(stroke
				(width 0.1524)
				(type default)
			)
			(layer "F.SilkS")
		)
		(fp_line
			(start -0.7874 0.4064)
			(end -0.7874 -0.4064)
			(stroke
				(width 0.1524)
				(type default)
			)
			(layer "F.SilkS")
		)
		(fp_line
			(start -0.12065 -0.305054)
			(end -0.12065 -0.2794)
			(stroke
				(width 0.1)
				(type default)
			)
			(layer "F.Fab")
		)
		(fp_line
			(start -0.67945 -0.305054)
			(end -0.12065 -0.305054)
			(stroke
				(width 0.1)
				(type default)
			)
			(layer "F.Fab")
		)
		(fp_line
			(start 0.67945 -0.3048)
			(end 0.67945 0.3048)
			(stroke
				(width 0.1)
				(type default)
			)
			(layer "F.Fab")
		)
		(fp_line
			(start 0.12065 -0.3048)
			(end 0.67945 -0.3048)
			(stroke
				(width 0.1)
				(type default)
			)
			(layer "F.Fab")
		)
		(fp_line
			(start 0.12065 -0.2794)
			(end 0.12065 -0.3048)
			(stroke
				(width 0.1)
				(type default)
			)
			(layer "F.Fab")
		)
		(fp_line
			(start -0.12065 -0.2794)
			(end 0.12065 -0.2794)
			(stroke
				(width 0.1)
				(type default)
			)
			(layer "F.Fab")
		)
		(fp_line
			(start 0.120396 0.2794)
			(end -0.12065 0.2794)
			(stroke
				(width 0.1)
				(type default)
			)
			(layer "F.Fab")
		)
		(fp_line
			(start -0.12065 0.2794)
			(end -0.12065 0.3048)
			(stroke
				(width 0.1)
				(type default)
			)
			(layer "F.Fab")
		)
		(fp_line
			(start 0.67945 0.3048)
			(end 0.120396 0.3048)
			(stroke
				(width 0.1)
				(type default)
			)
			(layer "F.Fab")
		)
		(fp_line
			(start 0.120396 0.3048)
			(end 0.120396 0.2794)
			(stroke
				(width 0.1)
				(type default)
			)
			(layer "F.Fab")
		)
		(fp_line
			(start -0.12065 0.3048)
			(end -0.67945 0.3048)
			(stroke
				(width 0.1)
				(type default)
			)
			(layer "F.Fab")
		)
		(fp_line
			(start -0.67945 0.3048)
			(end -0.67945 -0.305054)
			(stroke
				(width 0.1)
				(type default)
			)
			(layer "F.Fab")
		)
		(pad "1" smd circle
			(at -0.40005 0 90)
			(size 0 0)
			(layers "F.Cu" "F.Mask" "F.Paste")
			(net "FG_SS_EN")
		)
		(pad "2" smd circle
			(at 0.40005 0 90)
			(size 0 0)
			(layers "F.Cu" "F.Mask" "F.Paste")
			(net "GND")
		)
	)
)
